(kicad_pcb
	(version 20260206)
	(generator "pcbnew")
	(generator_version "10.0")
	(general
		(thickness 1.6)
		(legacy_teardrops no)
	)
	(paper "A4")
	(title_block
		(title "04192023_DAF0TMB3IC0_F0TG_MB_C_brd_V02_OCP.brd")
		(comment 1 "Grand Teton / footprint 2783 of 8354 (U26), pads 3558-3670 of 6102")
	)
	(layers
		(0 "F.Cu" signal "TOP")
		(4 "In1.Cu" signal "GND")
		(6 "In2.Cu" signal "IN1")
		(8 "In3.Cu" signal "GND1")
		(10 "In4.Cu" signal "IN2")
		(12 "In5.Cu" signal "GND2")
		(14 "In6.Cu" signal "IN3")
		(16 "In7.Cu" signal "GND3")
		(18 "In8.Cu" signal "VCC")
		(20 "In9.Cu" signal "VCC1")
		(22 "In10.Cu" signal "GND4")
		(24 "In11.Cu" signal "IN4")
		(26 "In12.Cu" signal "GND5")
		(28 "In13.Cu" signal "IN5")
		(30 "In14.Cu" signal "GND6")
		(32 "In15.Cu" signal "IN6")
		(34 "In16.Cu" signal "GND7")
		(2 "B.Cu" signal "BOTTOM")
		(9 "F.Adhes" user "F.Adhesive")
		(11 "B.Adhes" user "B.Adhesive")
		(13 "F.Paste" user "Package Geometry/Pastemask Top")
		(15 "B.Paste" user "Package Geometry/Pastemask Bottom")
		(5 "F.SilkS" user "Ref Des/Silkscreen Top")
		(7 "B.SilkS" user "Ref Des/Silkscreen Bottom")
		(1 "F.Mask" user "Board Geometry/Soldermask Top")
		(3 "B.Mask" user "Board Geometry/Soldermask Bottom")
		(17 "Dwgs.User" user "User.Drawings")
		(19 "Cmts.User" user "User.Comments")
		(21 "Eco1.User" user "User.Eco1")
		(23 "Eco2.User" user "User.Eco2")
		(25 "Edge.Cuts" user "Board Geometry/Outline")
		(27 "Margin" user)
		(31 "F.CrtYd" user "Package Geometry/Place Bound Top")
		(29 "B.CrtYd" user "Package Geometry/Place Bound Bottom")
		(35 "F.Fab" user "Ref Des/Assembly Top")
		(33 "B.Fab" user "Ref Des/Assembly Bottom")
	)
	(footprint ""
		(layer "F.Cu")
		(at 111.927894 -258.880356 180)
		(property "Reference" "U26"
			(at -45.05579 -61.794136 0)
			(unlocked yes)
			(layer "F.SilkS")
			(effects
				(font
					(size 0.7874 0.5842)
					(thickness 0.1524)
				)
			)
		)
		(property "Value" ""
			(at 0 0 180)
			(layer "F.Fab")
			(effects
				(font
					(size 1.27 1.27)
				)
			)
		)
		(duplicate_pad_numbers_are_jumpers no)
		(pad "CL30" smd circle
			(at -7.199884 22.23008 180)
			(size 0.450088 0.450088)
			(layers "F.Cu" "F.Mask" "F.Paste")
			(net "PVDDCR_CPU1_P1")
		)
		(pad "CL31" smd circle
			(at -6.260084 22.23008 180)
			(size 0.450088 0.450088)
			(layers "F.Cu" "F.Mask" "F.Paste")
			(net "GND")
		)
		(pad "CL32" smd circle
			(at -5.32003 22.23008 180)
			(size 0.450088 0.450088)
			(layers "F.Cu" "F.Mask" "F.Paste")
			(net "PVDDCR_CPU1_P1")
		)
		(pad "CL33" smd circle
			(at -4.379976 22.23008 180)
			(size 0.450088 0.450088)
			(layers "F.Cu" "F.Mask" "F.Paste")
			(net "PVDDCR_CPU1_P1")
		)
		(pad "CL34" smd circle
			(at -3.439922 22.23008 180)
			(size 0.450088 0.450088)
			(layers "F.Cu" "F.Mask" "F.Paste")
			(net "GND")
		)
		(pad "CL35" smd circle
			(at -2.500122 22.23008 180)
			(size 0.450088 0.450088)
			(layers "F.Cu" "F.Mask" "F.Paste")
			(net "GND")
		)
		(pad "CL36" smd circle
			(at -1.560068 22.23008 180)
			(size 0.450088 0.450088)
			(layers "F.Cu" "F.Mask" "F.Paste")
			(net "GND")
		)
		(pad "CL40" smd circle
			(at 1.260094 22.23008 180)
			(size 0.450088 0.450088)
			(layers "F.Cu" "F.Mask" "F.Paste")
			(net "GND")
		)
		(pad "CL41" smd circle
			(at 2.199894 22.23008 180)
			(size 0.450088 0.450088)
			(layers "F.Cu" "F.Mask" "F.Paste")
			(net "GND")
		)
		(pad "CL42" smd circle
			(at 3.139948 22.23008 180)
			(size 0.450088 0.450088)
			(layers "F.Cu" "F.Mask" "F.Paste")
			(net "GND")
		)
		(pad "CL43" smd circle
			(at 4.080002 22.23008 180)
			(size 0.450088 0.450088)
			(layers "F.Cu" "F.Mask" "F.Paste")
			(net "PVDDCR_CPU1_P1")
		)
		(pad "CL44" smd circle
			(at 5.020056 22.23008 180)
			(size 0.450088 0.450088)
			(layers "F.Cu" "F.Mask" "F.Paste")
			(net "PVDDCR_CPU1_P1")
		)
		(pad "CL45" smd circle
			(at 5.96011 22.23008 180)
			(size 0.450088 0.450088)
			(layers "F.Cu" "F.Mask" "F.Paste")
			(net "GND")
		)
		(pad "CL46" smd circle
			(at 6.89991 22.23008 180)
			(size 0.450088 0.450088)
			(layers "F.Cu" "F.Mask" "F.Paste")
			(net "PVDDCR_CPU1_P1")
		)
		(pad "CL47" smd circle
			(at 7.839964 22.23008 180)
			(size 0.450088 0.450088)
			(layers "F.Cu" "F.Mask" "F.Paste")
			(net "PVDDCR_CPU1_P1")
		)
		(pad "CL48" smd circle
			(at 8.780018 22.23008 180)
			(size 0.450088 0.450088)
			(layers "F.Cu" "F.Mask" "F.Paste")
			(net "GND")
		)
		(pad "CL49" smd circle
			(at 9.720072 22.23008 180)
			(size 0.450088 0.450088)
			(layers "F.Cu" "F.Mask" "F.Paste")
			(net "P5E_CPU1_P0_TX_DN<6>")
		)
		(pad "CL50" smd circle
			(at 10.659872 22.23008 180)
			(size 0.450088 0.450088)
			(layers "F.Cu" "F.Mask" "F.Paste")
			(net "P5E_CPU1_P0_TX_DP<6>")
		)
		(pad "CL51" smd circle
			(at 11.599926 22.23008 180)
			(size 0.450088 0.450088)
			(layers "F.Cu" "F.Mask" "F.Paste")
			(net "GND")
		)
		(pad "CL52" smd circle
			(at 12.53998 22.23008 180)
			(size 0.450088 0.450088)
			(layers "F.Cu" "F.Mask" "F.Paste")
			(net "P5E_CPU1_P0_TX_DN<2>")
		)
		(pad "CL53" smd circle
			(at 13.480034 22.23008 180)
			(size 0.450088 0.450088)
			(layers "F.Cu" "F.Mask" "F.Paste")
			(net "P5E_CPU1_P0_TX_DP<2>")
		)
		(pad "CL54" smd circle
			(at 14.420088 22.23008 180)
			(size 0.450088 0.450088)
			(layers "F.Cu" "F.Mask" "F.Paste")
			(net "GND")
		)
		(pad "CL55" smd circle
			(at 15.359888 22.23008 180)
			(size 0.450088 0.450088)
			(layers "F.Cu" "F.Mask" "F.Paste")
			(net "M_C_CPU1_SB_DQS_DN<6>")
		)
		(pad "CL56" smd circle
			(at 16.299942 22.23008 180)
			(size 0.450088 0.450088)
			(layers "F.Cu" "F.Mask" "F.Paste")
			(net "GND")
		)
		(pad "CL57" smd circle
			(at 17.239996 22.23008 180)
			(size 0.450088 0.450088)
			(layers "F.Cu" "F.Mask" "F.Paste")
			(net "M_C_CPU1_SB_DQS_DN<1>")
		)
		(pad "CL58" smd circle
			(at 18.18005 22.23008 180)
			(size 0.450088 0.450088)
			(layers "F.Cu" "F.Mask" "F.Paste")
			(net "GND")
		)
		(pad "CL59" smd circle
			(at 19.120104 22.23008 180)
			(size 0.450088 0.450088)
			(layers "F.Cu" "F.Mask" "F.Paste")
			(net "M_D_CPU1_SB_DQS_DN<6>")
		)
		(pad "CL60" smd circle
			(at 20.059904 22.23008 180)
			(size 0.450088 0.450088)
			(layers "F.Cu" "F.Mask" "F.Paste")
			(net "M_D_CPU1_SB_DQS_DN<1>")
		)
		(pad "CL61" smd circle
			(at 20.999958 22.23008 180)
			(size 0.450088 0.450088)
			(layers "F.Cu" "F.Mask" "F.Paste")
			(net "GND")
		)
		(pad "CL62" smd circle
			(at 21.940012 22.23008 180)
			(size 0.450088 0.450088)
			(layers "F.Cu" "F.Mask" "F.Paste")
			(net "M_B_CPU1_SB_DQS_DN<6>")
		)
		(pad "CL63" smd circle
			(at 22.880066 22.23008 180)
			(size 0.450088 0.450088)
			(layers "F.Cu" "F.Mask" "F.Paste")
			(net "GND")
		)
		(pad "CL64" smd circle
			(at 23.82012 22.23008 180)
			(size 0.450088 0.450088)
			(layers "F.Cu" "F.Mask" "F.Paste")
			(net "M_B_CPU1_SB_DQS_DN<1>")
		)
		(pad "CL65" smd circle
			(at 24.75992 22.23008 180)
			(size 0.450088 0.450088)
			(layers "F.Cu" "F.Mask" "F.Paste")
			(net "GND")
		)
		(pad "CL66" smd circle
			(at 25.699974 22.23008 180)
			(size 0.450088 0.450088)
			(layers "F.Cu" "F.Mask" "F.Paste")
			(net "M_F_CPU1_SB_DQS_DN<6>")
		)
		(pad "CL67" smd circle
			(at 26.640028 22.23008 180)
			(size 0.450088 0.450088)
			(layers "F.Cu" "F.Mask" "F.Paste")
			(net "M_F_CPU1_SB_DQS_DN<1>")
		)
		(pad "CL68" smd circle
			(at 27.580082 22.23008 180)
			(size 0.450088 0.450088)
			(layers "F.Cu" "F.Mask" "F.Paste")
			(net "GND")
		)
		(pad "CL69" smd circle
			(at 28.519882 22.23008 180)
			(size 0.450088 0.450088)
			(layers "F.Cu" "F.Mask" "F.Paste")
			(net "M_E_CPU1_SB_DQS_DN<6>")
		)
		(pad "CL70" smd circle
			(at 29.459936 22.23008 180)
			(size 0.450088 0.450088)
			(layers "F.Cu" "F.Mask" "F.Paste")
			(net "GND")
		)
		(pad "CL71" smd circle
			(at 30.39999 22.23008 180)
			(size 0.450088 0.450088)
			(layers "F.Cu" "F.Mask" "F.Paste")
			(net "M_E_CPU1_SB_DQS_DN<1>")
		)
		(pad "CL72" smd circle
			(at 31.340044 22.23008 180)
			(size 0.450088 0.450088)
			(layers "F.Cu" "F.Mask" "F.Paste")
			(net "GND")
		)
		(pad "CL73" smd circle
			(at 32.280098 22.23008 180)
			(size 0.450088 0.450088)
			(layers "F.Cu" "F.Mask" "F.Paste")
			(net "M_A_CPU1_SB_DQS_DN<6>")
		)
		(pad "CL74" smd circle
			(at 33.219898 22.23008 180)
			(size 0.450088 0.450088)
			(layers "F.Cu" "F.Mask" "F.Paste")
			(net "M_A_CPU1_SB_DQS_DN<1>")
		)
		(pad "CL75" smd circle
			(at 34.159952 22.23008 180)
			(size 0.450088 0.450088)
			(layers "F.Cu" "F.Mask" "F.Paste")
			(net "GND")
		)
		(pad "CM2" smd circle
			(at -33.990026 23.040086 180)
			(size 0.450088 0.450088)
			(layers "F.Cu" "F.Mask" "F.Paste")
			(net "M_G_CPU1_SB_DQ<12>")
		)
		(pad "CM3" smd circle
			(at -33.049972 23.040086 180)
			(size 0.450088 0.450088)
			(layers "F.Cu" "F.Mask" "F.Paste")
			(net "GND")
		)
		(pad "CM4" smd circle
			(at -32.109918 23.040086 180)
			(size 0.450088 0.450088)
			(layers "F.Cu" "F.Mask" "F.Paste")
			(net "M_G_CPU1_SB_DQS_DP<6>")
		)
		(pad "CM5" smd circle
			(at -31.170118 23.040086 180)
			(size 0.450088 0.450088)
			(layers "F.Cu" "F.Mask" "F.Paste")
			(net "GND")
		)
		(pad "CM6" smd circle
			(at -30.230064 23.040086 180)
			(size 0.450088 0.450088)
			(layers "F.Cu" "F.Mask" "F.Paste")
			(net "M_K_CPU1_SB_DQ<12>")
		)
		(pad "CM7" smd circle
			(at -29.29001 23.040086 180)
			(size 0.450088 0.450088)
			(layers "F.Cu" "F.Mask" "F.Paste")
			(net "M_K_CPU1_SB_DQS_DP<6>")
		)
		(pad "CM8" smd circle
			(at -28.349956 23.040086 180)
			(size 0.450088 0.450088)
			(layers "F.Cu" "F.Mask" "F.Paste")
			(net "GND")
		)
		(pad "CM9" smd circle
			(at -27.409902 23.040086 180)
			(size 0.450088 0.450088)
			(layers "F.Cu" "F.Mask" "F.Paste")
			(net "M_L_CPU1_SB_DQ<12>")
		)
		(pad "CM10" smd circle
			(at -26.470102 23.040086 180)
			(size 0.450088 0.450088)
			(layers "F.Cu" "F.Mask" "F.Paste")
			(net "GND")
		)
		(pad "CM11" smd circle
			(at -25.530048 23.040086 180)
			(size 0.450088 0.450088)
			(layers "F.Cu" "F.Mask" "F.Paste")
			(net "M_L_CPU1_SB_DQS_DP<6>")
		)
		(pad "CM12" smd circle
			(at -24.589994 23.040086 180)
			(size 0.450088 0.450088)
			(layers "F.Cu" "F.Mask" "F.Paste")
			(net "GND")
		)
		(pad "CM13" smd circle
			(at -23.64994 23.040086 180)
			(size 0.450088 0.450088)
			(layers "F.Cu" "F.Mask" "F.Paste")
			(net "M_H_CPU1_SB_DQ<12>")
		)
		(pad "CM14" smd circle
			(at -22.709886 23.040086 180)
			(size 0.450088 0.450088)
			(layers "F.Cu" "F.Mask" "F.Paste")
			(net "M_H_CPU1_SB_DQS_DP<6>")
		)
		(pad "CM15" smd circle
			(at -21.770086 23.040086 180)
			(size 0.450088 0.450088)
			(layers "F.Cu" "F.Mask" "F.Paste")
			(net "GND")
		)
		(pad "CM16" smd circle
			(at -20.830032 23.040086 180)
			(size 0.450088 0.450088)
			(layers "F.Cu" "F.Mask" "F.Paste")
			(net "M_J_CPU1_SB_DQ<12>")
		)
		(pad "CM17" smd circle
			(at -19.889978 23.040086 180)
			(size 0.450088 0.450088)
			(layers "F.Cu" "F.Mask" "F.Paste")
			(net "GND")
		)
		(pad "CM18" smd circle
			(at -18.949924 23.040086 180)
			(size 0.450088 0.450088)
			(layers "F.Cu" "F.Mask" "F.Paste")
			(net "M_J_CPU1_SB_DQS_DP<6>")
		)
		(pad "CM19" smd circle
			(at -18.010124 23.040086 180)
			(size 0.450088 0.450088)
			(layers "F.Cu" "F.Mask" "F.Paste")
			(net "GND")
		)
		(pad "CM20" smd circle
			(at -17.07007 23.040086 180)
			(size 0.450088 0.450088)
			(layers "F.Cu" "F.Mask" "F.Paste")
			(net "M_I_CPU1_SB_DQ<12>")
		)
		(pad "CM21" smd circle
			(at -16.130016 23.040086 180)
			(size 0.450088 0.450088)
			(layers "F.Cu" "F.Mask" "F.Paste")
			(net "M_I_CPU1_SB_DQS_DP<6>")
		)
		(pad "CM22" smd circle
			(at -15.189962 23.040086 180)
			(size 0.450088 0.450088)
			(layers "F.Cu" "F.Mask" "F.Paste")
			(net "PVDD11_S3_P1")
		)
		(pad "CM23" smd circle
			(at -14.249908 23.040086 180)
			(size 0.450088 0.450088)
			(layers "F.Cu" "F.Mask" "F.Paste")
			(net "GND")
		)
		(pad "CM24" smd circle
			(at -13.310108 23.040086 180)
			(size 0.450088 0.450088)
			(layers "F.Cu" "F.Mask" "F.Paste")
			(net "GND")
		)
		(pad "CM25" smd circle
			(at -12.370054 23.040086 180)
			(size 0.450088 0.450088)
			(layers "F.Cu" "F.Mask" "F.Paste")
			(net "GND")
		)
		(pad "CM26" smd circle
			(at -11.43 23.040086 180)
			(size 0.450088 0.450088)
			(layers "F.Cu" "F.Mask" "F.Paste")
			(net "GND")
		)
		(pad "CM27" smd circle
			(at -10.489946 23.040086 180)
			(size 0.450088 0.450088)
			(layers "F.Cu" "F.Mask" "F.Paste")
			(net "GND")
		)
		(pad "CM28" smd circle
			(at -9.549892 23.040086 180)
			(size 0.450088 0.450088)
			(layers "F.Cu" "F.Mask" "F.Paste")
			(net "GND")
		)
		(pad "CM29" smd circle
			(at -8.610092 23.040086 180)
			(size 0.450088 0.450088)
			(layers "F.Cu" "F.Mask" "F.Paste")
			(net "GND")
		)
		(pad "CM30" smd circle
			(at -7.670038 23.040086 180)
			(size 0.450088 0.450088)
			(layers "F.Cu" "F.Mask" "F.Paste")
			(net "GND")
		)
		(pad "CM31" smd circle
			(at -6.729984 23.040086 180)
			(size 0.450088 0.450088)
			(layers "F.Cu" "F.Mask" "F.Paste")
			(net "GND")
		)
		(pad "CM32" smd circle
			(at -5.78993 23.040086 180)
			(size 0.450088 0.450088)
			(layers "F.Cu" "F.Mask" "F.Paste")
			(net "GND")
		)
		(pad "CM33" smd circle
			(at -4.849876 23.040086 180)
			(size 0.450088 0.450088)
			(layers "F.Cu" "F.Mask" "F.Paste")
			(net "GND")
		)
		(pad "CM34" smd circle
			(at -3.910076 23.040086 180)
			(size 0.450088 0.450088)
			(layers "F.Cu" "F.Mask" "F.Paste")
			(net "GND")
		)
		(pad "CM35" smd circle
			(at -2.970022 23.040086 180)
			(size 0.450088 0.450088)
			(layers "F.Cu" "F.Mask" "F.Paste")
			(net "P5E_CPU1_P2_RX_DP<0>")
		)
		(pad "CM36" smd circle
			(at -2.029968 23.040086 180)
			(size 0.450088 0.450088)
			(layers "F.Cu" "F.Mask" "F.Paste")
			(net "P5E_CPU1_P2_RX_DN<0>")
		)
		(pad "CM37" smd circle
			(at -1.089914 23.040086 180)
			(size 0.450088 0.450088)
			(layers "F.Cu" "F.Mask" "F.Paste")
			(net "GND")
		)
		(pad "CM39" smd circle
			(at 0.78994 23.040086 180)
			(size 0.450088 0.450088)
			(layers "F.Cu" "F.Mask" "F.Paste")
			(net "GND")
		)
		(pad "CM40" smd circle
			(at 1.729994 23.040086 180)
			(size 0.450088 0.450088)
			(layers "F.Cu" "F.Mask" "F.Paste")
			(net "P5E_CPU1_P0_TX_DN<15>")
		)
		(pad "CM41" smd circle
			(at 2.670048 23.040086 180)
			(size 0.450088 0.450088)
			(layers "F.Cu" "F.Mask" "F.Paste")
			(net "P5E_CPU1_P0_TX_DP<15>")
		)
		(pad "CM42" smd circle
			(at 3.610102 23.040086 180)
			(size 0.450088 0.450088)
			(layers "F.Cu" "F.Mask" "F.Paste")
			(net "GND")
		)
		(pad "CM43" smd circle
			(at 4.549902 23.040086 180)
			(size 0.450088 0.450088)
			(layers "F.Cu" "F.Mask" "F.Paste")
			(net "GND")
		)
		(pad "CM44" smd circle
			(at 5.489956 23.040086 180)
			(size 0.450088 0.450088)
			(layers "F.Cu" "F.Mask" "F.Paste")
			(net "GND")
		)
		(pad "CM45" smd circle
			(at 6.43001 23.040086 180)
			(size 0.450088 0.450088)
			(layers "F.Cu" "F.Mask" "F.Paste")
			(net "GND")
		)
		(pad "CM46" smd circle
			(at 7.370064 23.040086 180)
			(size 0.450088 0.450088)
			(layers "F.Cu" "F.Mask" "F.Paste")
			(net "GND")
		)
		(pad "CM47" smd circle
			(at 8.310118 23.040086 180)
			(size 0.450088 0.450088)
			(layers "F.Cu" "F.Mask" "F.Paste")
			(net "GND")
		)
		(pad "CM48" smd circle
			(at 9.249918 23.040086 180)
			(size 0.450088 0.450088)
			(layers "F.Cu" "F.Mask" "F.Paste")
			(net "GND")
		)
		(pad "CM49" smd circle
			(at 10.189972 23.040086 180)
			(size 0.450088 0.450088)
			(layers "F.Cu" "F.Mask" "F.Paste")
			(net "GND")
		)
		(pad "CM50" smd circle
			(at 11.130026 23.040086 180)
			(size 0.450088 0.450088)
			(layers "F.Cu" "F.Mask" "F.Paste")
			(net "GND")
		)
		(pad "CM51" smd circle
			(at 12.07008 23.040086 180)
			(size 0.450088 0.450088)
			(layers "F.Cu" "F.Mask" "F.Paste")
			(net "GND")
		)
		(pad "CM52" smd circle
			(at 13.00988 23.040086 180)
			(size 0.450088 0.450088)
			(layers "F.Cu" "F.Mask" "F.Paste")
			(net "GND")
		)
		(pad "CM53" smd circle
			(at 13.949934 23.040086 180)
			(size 0.450088 0.450088)
			(layers "F.Cu" "F.Mask" "F.Paste")
			(net "GND")
		)
		(pad "CM54" smd circle
			(at 14.889988 23.040086 180)
			(size 0.450088 0.450088)
			(layers "F.Cu" "F.Mask" "F.Paste")
			(net "PVDDIO_P1")
		)
		(pad "CM55" smd circle
			(at 15.830042 23.040086 180)
			(size 0.450088 0.450088)
			(layers "F.Cu" "F.Mask" "F.Paste")
			(net "M_C_CPU1_SB_DQS_DP<6>")
		)
		(pad "CM56" smd circle
			(at 16.770096 23.040086 180)
			(size 0.450088 0.450088)
			(layers "F.Cu" "F.Mask" "F.Paste")
			(net "M_C_CPU1_SB_DQ<12>")
		)
		(pad "CM57" smd circle
			(at 17.709896 23.040086 180)
			(size 0.450088 0.450088)
			(layers "F.Cu" "F.Mask" "F.Paste")
			(net "GND")
		)
		(pad "CM58" smd circle
			(at 18.64995 23.040086 180)
			(size 0.450088 0.450088)
			(layers "F.Cu" "F.Mask" "F.Paste")
			(net "M_D_CPU1_SB_DQS_DP<6>")
		)
		(pad "CM59" smd circle
			(at 19.590004 23.040086 180)
			(size 0.450088 0.450088)
			(layers "F.Cu" "F.Mask" "F.Paste")
			(net "GND")
		)
		(pad "CM60" smd circle
			(at 20.530058 23.040086 180)
			(size 0.450088 0.450088)
			(layers "F.Cu" "F.Mask" "F.Paste")
			(net "M_D_CPU1_SB_DQ<12>")
		)
		(pad "CM61" smd circle
			(at 21.470112 23.040086 180)
			(size 0.450088 0.450088)
			(layers "F.Cu" "F.Mask" "F.Paste")
			(net "GND")
		)
		(pad "CM62" smd circle
			(at 22.409912 23.040086 180)
			(size 0.450088 0.450088)
			(layers "F.Cu" "F.Mask" "F.Paste")
			(net "M_B_CPU1_SB_DQS_DP<6>")
		)
		(pad "CM63" smd circle
			(at 23.349966 23.040086 180)
			(size 0.450088 0.450088)
			(layers "F.Cu" "F.Mask" "F.Paste")
			(net "M_B_CPU1_SB_DQ<12>")
		)
		(pad "CM64" smd circle
			(at 24.29002 23.040086 180)
			(size 0.450088 0.450088)
			(layers "F.Cu" "F.Mask" "F.Paste")
			(net "GND")
		)
		(pad "CM65" smd circle
			(at 25.230074 23.040086 180)
			(size 0.450088 0.450088)
			(layers "F.Cu" "F.Mask" "F.Paste")
			(net "M_F_CPU1_SB_DQS_DP<6>")
		)
		(pad "CM66" smd circle
			(at 26.170128 23.040086 180)
			(size 0.450088 0.450088)
			(layers "F.Cu" "F.Mask" "F.Paste")
			(net "GND")
		)
		(pad "CM67" smd circle
			(at 27.109928 23.040086 180)
			(size 0.450088 0.450088)
			(layers "F.Cu" "F.Mask" "F.Paste")
			(net "M_F_CPU1_SB_DQ<12>")
		)
		(pad "CM68" smd circle
			(at 28.049982 23.040086 180)
			(size 0.450088 0.450088)
			(layers "F.Cu" "F.Mask" "F.Paste")
			(net "GND")
		)
		(pad "CM69" smd circle
			(at 28.990036 23.040086 180)
			(size 0.450088 0.450088)
			(layers "F.Cu" "F.Mask" "F.Paste")
			(net "M_E_CPU1_SB_DQS_DP<6>")
		)
		(pad "CM70" smd circle
			(at 29.93009 23.040086 180)
			(size 0.450088 0.450088)
			(layers "F.Cu" "F.Mask" "F.Paste")
			(net "M_E_CPU1_SB_DQ<12>")
		)
		(pad "CM71" smd circle
			(at 30.86989 23.040086 180)
			(size 0.450088 0.450088)
			(layers "F.Cu" "F.Mask" "F.Paste")
			(net "GND")
		)
		(pad "CM72" smd circle
			(at 31.809944 23.040086 180)
			(size 0.450088 0.450088)
			(layers "F.Cu" "F.Mask" "F.Paste")
			(net "M_A_CPU1_SB_DQS_DP<6>")
		)
	)
)
